# T6G (Grand Teton) — schematic netlist excerpt (pin names and nets, part order shuffled) for the footprints in the layout excerpt that follows; sources: Cadence DE-HDL packaged netlist, KiCad conversion of 04192023_DAF0TMB3IC0_F0TG_MB_C_brd_V02_OCP.brd

C690  Q_CAP_DIFFBUS  DIFF BUS_0.22UF 6.3V 20% X6S  pkg C0201  page 67 : \1\ = P5E_CPU1_G1_TX_C_DN<9> ; \2\ = P5E_CPU1_G1_TX_DN<9>
PC403_4  Q_CAP  0.1UF 25V 10% X7R  pkg 0402  page 219 : A = PVDDCR_CPU1_P1_VCCS ; B = GND
R1518  Q_RES  0 5% CHIP  pkg 0402LF  page 136 : A = HP_LVC3_OCP_V3_1_PWRGD_R2 ; B = OCP_V3_1_P3V3_R3_PWRGD

(kicad_pcb
	(version 20260206)
	(generator "pcbnew")
	(generator_version "10.0")
	(general
		(thickness 1.6)
		(legacy_teardrops no)
	)
	(paper "A4")
	(title_block
		(title "04192023_DAF0TMB3IC0_F0TG_MB_C_brd_V02_OCP.brd")
		(comment 1 "Grand Teton / footprints 698-700 of 8354")
	)
	(layers
		(0 "F.Cu" signal "TOP")
		(4 "In1.Cu" signal "GND")
		(6 "In2.Cu" signal "IN1")
		(8 "In3.Cu" signal "GND1")
		(10 "In4.Cu" signal "IN2")
		(12 "In5.Cu" signal "GND2")
		(14 "In6.Cu" signal "IN3")
		(16 "In7.Cu" signal "GND3")
		(18 "In8.Cu" signal "VCC")
		(20 "In9.Cu" signal "VCC1")
		(22 "In10.Cu" signal "GND4")
		(24 "In11.Cu" signal "IN4")
		(26 "In12.Cu" signal "GND5")
		(28 "In13.Cu" signal "IN5")
		(30 "In14.Cu" signal "GND6")
		(32 "In15.Cu" signal "IN6")
		(34 "In16.Cu" signal "GND7")
		(2 "B.Cu" signal "BOTTOM")
		(9 "F.Adhes" user "F.Adhesive")
		(11 "B.Adhes" user "B.Adhesive")
		(13 "F.Paste" user "Package Geometry/Pastemask Top")
		(15 "B.Paste" user "Package Geometry/Pastemask Bottom")
		(5 "F.SilkS" user "Ref Des/Silkscreen Top")
		(7 "B.SilkS" user "Ref Des/Silkscreen Bottom")
		(1 "F.Mask" user "Board Geometry/Soldermask Top")
		(3 "B.Mask" user "Board Geometry/Soldermask Bottom")
		(17 "Dwgs.User" user "User.Drawings")
		(19 "Cmts.User" user "User.Comments")
		(21 "Eco1.User" user "User.Eco1")
		(23 "Eco2.User" user "User.Eco2")
		(25 "Edge.Cuts" user "Board Geometry/Outline")
		(27 "Margin" user)
		(31 "F.CrtYd" user "Package Geometry/Place Bound Top")
		(29 "B.CrtYd" user "Package Geometry/Place Bound Bottom")
		(35 "F.Fab" user "Ref Des/Assembly Top")
		(33 "B.Fab" user "Ref Des/Assembly Bottom")
	)
	(footprint ""
		(layer "F.Cu")
		(at 59.18073 -351.578672 90)
		(property "Reference" "PC403_4"
			(at 0 0 90)
			(layer "F.SilkS")
			(hide yes)
			(effects
				(font
					(size 1.27 1.27)
				)
			)
		)
		(property "Value" ""
			(at 0 0 90)
			(layer "F.Fab")
			(effects
				(font
					(size 1.27 1.27)
				)
			)
		)
		(duplicate_pad_numbers_are_jumpers no)
		(fp_line
			(start 0.7874 -0.4064)
			(end 0.7874 0.4064)
			(stroke
				(width 0.1524)
				(type default)
			)
			(layer "F.SilkS")
		)
		(fp_line
			(start -0.7874 -0.4064)
			(end 0.7874 -0.4064)
			(stroke
				(width 0.1524)
				(type default)
			)
			(layer "F.SilkS")
		)
		(fp_line
			(start 0.7874 0.4064)
			(end -0.7874 0.4064)
			(stroke
				(width 0.1524)
				(type default)
			)
			(layer "F.SilkS")
		)
		(fp_line
			(start -0.7874 0.4064)
			(end -0.7874 -0.4064)
			(stroke
				(width 0.1524)
				(type default)
			)
			(layer "F.SilkS")
		)
		(fp_line
			(start -0.12065 -0.305054)
			(end -0.12065 -0.2794)
			(stroke
				(width 0.1)
				(type default)
			)
			(layer "F.Fab")
		)
		(fp_line
			(start -0.67945 -0.305054)
			(end -0.12065 -0.305054)
			(stroke
				(width 0.1)
				(type default)
			)
			(layer "F.Fab")
		)
		(fp_line
			(start 0.67945 -0.3048)
			(end 0.67945 0.3048)
			(stroke
				(width 0.1)
				(type default)
			)
			(layer "F.Fab")
		)
		(fp_line
			(start 0.12065 -0.3048)
			(end 0.67945 -0.3048)
			(stroke
				(width 0.1)
				(type default)
			)
			(layer "F.Fab")
		)
		(fp_line
			(start 0.12065 -0.2794)
			(end 0.12065 -0.3048)
			(stroke
				(width 0.1)
				(type default)
			)
			(layer "F.Fab")
		)
		(fp_line
			(start -0.12065 -0.2794)
			(end 0.12065 -0.2794)
			(stroke
				(width 0.1)
				(type default)
			)
			(layer "F.Fab")
		)
		(fp_line
			(start 0.120396 0.2794)
			(end -0.12065 0.2794)
			(stroke
				(width 0.1)
				(type default)
			)
			(layer "F.Fab")
		)
		(fp_line
			(start -0.12065 0.2794)
			(end -0.12065 0.3048)
			(stroke
				(width 0.1)
				(type default)
			)
			(layer "F.Fab")
		)
		(fp_line
			(start 0.67945 0.3048)
			(end 0.120396 0.3048)
			(stroke
				(width 0.1)
				(type default)
			)
			(layer "F.Fab")
		)
		(fp_line
			(start 0.120396 0.3048)
			(end 0.120396 0.2794)
			(stroke
				(width 0.1)
				(type default)
			)
			(layer "F.Fab")
		)
		(fp_line
			(start -0.12065 0.3048)
			(end -0.67945 0.3048)
			(stroke
				(width 0.1)
				(type default)
			)
			(layer "F.Fab")
		)
		(fp_line
			(start -0.67945 0.3048)
			(end -0.67945 -0.305054)
			(stroke
				(width 0.1)
				(type default)
			)
			(layer "F.Fab")
		)
		(pad "1" smd circle
			(at -0.40005 0 90)
			(size 0 0)
			(layers "F.Cu" "F.Mask" "F.Paste")
			(net "PVDDCR_CPU1_P1_VCCS")
		)
		(pad "2" smd circle
			(at 0.40005 0 90)
			(size 0 0)
			(layers "F.Cu" "F.Mask" "F.Paste")
			(net "GND")
		)
	)
	(footprint ""
		(layer "F.Cu")
		(at 32.272478 -16.099536 90)
		(property "Reference" "C690"
			(at 0 0 90)
			(layer "F.SilkS")
			(hide yes)
			(effects
				(font
					(size 1.27 1.27)
				)
			)
		)
		(property "Value" ""
			(at 0 0 90)
			(layer "F.Fab")
			(effects
				(font
					(size 1.27 1.27)
				)
			)
		)
		(duplicate_pad_numbers_are_jumpers no)
		(fp_line
			(start 0.299974 -0.150114)
			(end 0.299974 0.150114)
			(stroke
				(width 0.1)
				(type default)
			)
			(layer "F.Fab")
		)
		(fp_line
			(start -0.299974 -0.150114)
			(end 0.299974 -0.150114)
			(stroke
				(width 0.1)
				(type default)
			)
			(layer "F.Fab")
		)
		(fp_line
			(start 0.299974 0.150114)
			(end -0.299974 0.150114)
			(stroke
				(width 0.1)
				(type default)
			)
			(layer "F.Fab")
		)
		(fp_line
			(start -0.299974 0.150114)
			(end -0.299974 -0.150114)
			(stroke
				(width 0.1)
				(type default)
			)
			(layer "F.Fab")
		)
		(pad "1" smd rect
			(at -0.2667 0 90)
			(size 0.3048 0.381)
			(layers "F.Cu" "F.Mask" "F.Paste")
			(net "P5E_CPU1_G1_TX_C_DN<9>")
		)
		(pad "2" smd rect
			(at 0.2667 0 90)
			(size 0.3048 0.381)
			(layers "F.Cu" "F.Mask" "F.Paste")
			(net "P5E_CPU1_G1_TX_DN<9>")
		)
	)
	(footprint ""
		(layer "F.Cu")
		(at 220.98508 -106.35488)
		(property "Reference" "R1518"
			(at 0 0 0)
			(layer "F.SilkS")
			(hide yes)
			(effects
				(font
					(size 1.27 1.27)
				)
			)
		)
		(property "Value" ""
			(at 0 0 0)
			(layer "F.Fab")
			(effects
				(font
					(size 1.27 1.27)
				)
			)
		)
		(duplicate_pad_numbers_are_jumpers no)
		(fp_line
			(start -0.7874 -0.4064)
			(end 0.7874 -0.4064)
			(stroke
				(width 0.1524)
				(type default)
			)
			(layer "F.SilkS")
		)
		(fp_line
			(start -0.7874 0.4064)
			(end -0.7874 -0.4064)
			(stroke
				(width 0.1524)
				(type default)
			)
			(layer "F.SilkS")
		)
		(fp_line
			(start 0.7874 -0.4064)
			(end 0.7874 0.4064)
			(stroke
				(width 0.1524)
				(type default)
			)
			(layer "F.SilkS")
		)
		(fp_line
			(start 0.7874 0.4064)
			(end -0.7874 0.4064)
			(stroke
				(width 0.1524)
				(type default)
			)
			(layer "F.SilkS")
		)
		(fp_line
			(start -0.67945 -0.305054)
			(end -0.12065 -0.305054)
			(stroke
				(width 0.1)
				(type default)
			)
			(layer "F.Fab")
		)
		(fp_line
			(start -0.67945 0.3048)
			(end -0.67945 -0.305054)
			(stroke
				(width 0.1)
				(type default)
			)
			(layer "F.Fab")
		)
		(fp_line
			(start -0.12065 -0.305054)
			(end -0.12065 -0.2794)
			(stroke
				(width 0.1)
				(type default)
			)
			(layer "F.Fab")
		)
		(fp_line
			(start -0.12065 -0.2794)
			(end 0.12065 -0.2794)
			(stroke
				(width 0.1)
				(type default)
			)
			(layer "F.Fab")
		)
		(fp_line
			(start -0.12065 0.2794)
			(end -0.12065 0.3048)
			(stroke
				(width 0.1)
				(type default)
			)
			(layer "F.Fab")
		)
		(fp_line
			(start -0.12065 0.3048)
			(end -0.67945 0.3048)
			(stroke
				(width 0.1)
				(type default)
			)
			(layer "F.Fab")
		)
		(fp_line
			(start 0.120396 0.2794)
			(end -0.12065 0.2794)
			(stroke
				(width 0.1)
				(type default)
			)
			(layer "F.Fab")
		)
		(fp_line
			(start 0.120396 0.3048)
			(end 0.120396 0.2794)
			(stroke
				(width 0.1)
				(type default)
			)
			(layer "F.Fab")
		)
		(fp_line
			(start 0.12065 -0.3048)
			(end 0.67945 -0.3048)
			(stroke
				(width 0.1)
				(type default)
			)
			(layer "F.Fab")
		)
		(fp_line
			(start 0.12065 -0.2794)
			(end 0.12065 -0.3048)
			(stroke
				(width 0.1)
				(type default)
			)
			(layer "F.Fab")
		)
		(fp_line
			(start 0.67945 -0.3048)
			(end 0.67945 0.3048)
			(stroke
				(width 0.1)
				(type default)
			)
			(layer "F.Fab")
		)
		(fp_line
			(start 0.67945 0.3048)
			(end 0.120396 0.3048)
			(stroke
				(width 0.1)
				(type default)
			)
			(layer "F.Fab")
		)
		(pad "1" smd circle
			(at -0.40005 0)
			(size 0 0)
			(layers "F.Cu" "F.Mask" "F.Paste")
			(net "HP_LVC3_OCP_V3_1_PWRGD_R2")
		)
		(pad "2" smd circle
			(at 0.40005 0)
			(size 0 0)
			(layers "F.Cu" "F.Mask" "F.Paste")
			(net "OCP_V3_1_P3V3_R3_PWRGD")
		)
	)
)
